(kicad_pcb
	(version 20260206)
	(generator "pcbnew")
	(generator_version "10.0")
	(general
		(thickness 1.6)
		(legacy_teardrops no)
	)
	(paper "A4")
	(title_block
		(title "03242023_DA0F0TMBIJ0_F0T_Motherboard_J_brd_V01_OCP.brd")
		(comment 1 "Grand Teton / footprint 1682 of 6105 (U1), pads 3246-3348 of 4677")
	)
	(layers
		(0 "F.Cu" signal "TOP")
		(4 "In1.Cu" signal "GND")
		(6 "In2.Cu" signal "IN1")
		(8 "In3.Cu" signal "GND1")
		(10 "In4.Cu" signal "IN2")
		(12 "In5.Cu" signal "GND2")
		(14 "In6.Cu" signal "IN3")
		(16 "In7.Cu" signal "GND3")
		(18 "In8.Cu" signal "VCC")
		(20 "In9.Cu" signal "VCC1")
		(22 "In10.Cu" signal "GND4")
		(24 "In11.Cu" signal "IN4")
		(26 "In12.Cu" signal "GND5")
		(28 "In13.Cu" signal "IN5")
		(30 "In14.Cu" signal "GND6")
		(32 "In15.Cu" signal "IN6")
		(34 "In16.Cu" signal "GND7")
		(2 "B.Cu" signal "BOTTOM")
		(9 "F.Adhes" user "F.Adhesive")
		(11 "B.Adhes" user "B.Adhesive")
		(13 "F.Paste" user "Package Geometry/Pastemask Top")
		(15 "B.Paste" user "Package Geometry/Pastemask Bottom")
		(5 "F.SilkS" user "Ref Des/Silkscreen Top")
		(7 "B.SilkS" user "Ref Des/Silkscreen Bottom")
		(1 "F.Mask" user "Board Geometry/Soldermask Top")
		(3 "B.Mask" user "Board Geometry/Soldermask Bottom")
		(17 "Dwgs.User" user "User.Drawings")
		(19 "Cmts.User" user "User.Comments")
		(21 "Eco1.User" user "User.Eco1")
		(23 "Eco2.User" user "User.Eco2")
		(25 "Edge.Cuts" user "Board Geometry/Outline")
		(27 "Margin" user)
		(31 "F.CrtYd" user "Package Geometry/Place Bound Top")
		(29 "B.CrtYd" user "Package Geometry/Place Bound Bottom")
		(35 "F.Fab" user "Ref Des/Assembly Top")
		(33 "B.Fab" user "Ref Des/Assembly Bottom")
	)
	(footprint ""
		(layer "F.Cu")
		(at 111.93018 -251.76988 90)
		(property "Reference" "U1"
			(at -74.913236 41.548812 0)
			(unlocked yes)
			(layer "F.SilkS")
			(effects
				(font
					(size 1.6002 1.1938)
					(thickness 0.1524)
				)
				(justify left)
			)
		)
		(property "Value" ""
			(at 0 0 90)
			(layer "F.Fab")
			(effects
				(font
					(size 1.27 1.27)
				)
			)
		)
		(duplicate_pad_numbers_are_jumpers no)
		(pad "DY2" smd circle
			(at -36.611306 19.445732 270)
			(size 0.4318 0.4318)
			(layers "F.Cu" "F.Mask" "F.Paste")
			(net "UPI_CPU0_CPU1_P0P1_DN<4>")
		)
		(pad "DY4" smd circle
			(at -34.98342 19.445732 270)
			(size 0.4318 0.4318)
			(layers "F.Cu" "F.Mask" "F.Paste")
			(net "GND")
		)
		(pad "DY6" smd circle
			(at -33.355534 19.445732 270)
			(size 0.4318 0.4318)
			(layers "F.Cu" "F.Mask" "F.Paste")
			(net "UPI_CPU1_CPU0_P1P0_DN<3>")
		)
		(pad "DY8" smd circle
			(at -31.727902 19.445732 270)
			(size 0.4318 0.4318)
			(layers "F.Cu" "F.Mask" "F.Paste")
			(net "GND")
		)
		(pad "DY10" smd circle
			(at -30.100016 19.445732 270)
			(size 0.4318 0.4318)
			(layers "F.Cu" "F.Mask" "F.Paste")
			(net "P5E_CPU1_PE2_RX_DN<11>")
		)
		(pad "DY12" smd circle
			(at -28.472384 19.445732 270)
			(size 0.4318 0.4318)
			(layers "F.Cu" "F.Mask" "F.Paste")
			(net "GND")
		)
		(pad "DY14" smd circle
			(at -26.844498 19.445732 270)
			(size 0.4318 0.4318)
			(layers "F.Cu" "F.Mask" "F.Paste")
			(net "P5E_CPU1_PE2_TX_DP<12>")
		)
		(pad "DY16" smd circle
			(at -25.216612 19.445732 270)
			(size 0.4318 0.4318)
			(layers "F.Cu" "F.Mask" "F.Paste")
			(net "GND")
		)
		(pad "DY18" smd circle
			(at -23.58898 19.445732 270)
			(size 0.4318 0.4318)
			(layers "F.Cu" "F.Mask" "F.Paste")
			(net "M_F_CPU1_SB_DQS_DN<8>")
		)
		(pad "DY20" smd circle
			(at -21.961094 19.445732 270)
			(size 0.4318 0.4318)
			(layers "F.Cu" "F.Mask" "F.Paste")
			(net "M_F_CPU1_SB_DQ<26>")
		)
		(pad "DY22" smd circle
			(at -20.333462 19.445732 270)
			(size 0.4318 0.4318)
			(layers "F.Cu" "F.Mask" "F.Paste")
			(net "M_G_CPU1_SB_DQ<23>")
		)
		(pad "DY24" smd circle
			(at -18.705576 19.445732 270)
			(size 0.4318 0.4318)
			(layers "F.Cu" "F.Mask" "F.Paste")
			(net "M_G_CPU1_SB_DQS_DP<7>")
		)
		(pad "DY26" smd circle
			(at -17.07769 19.445732 270)
			(size 0.4318 0.4318)
			(layers "F.Cu" "F.Mask" "F.Paste")
			(net "M_G_CPU1_SB_DQ<18>")
		)
		(pad "DY28" smd circle
			(at -15.450058 19.445732 270)
			(size 0.4318 0.4318)
			(layers "F.Cu" "F.Mask" "F.Paste")
			(net "M_F_CPU1_SB_DQ<7>")
		)
		(pad "DY30" smd circle
			(at -13.822426 19.445732 270)
			(size 0.4318 0.4318)
			(layers "F.Cu" "F.Mask" "F.Paste")
			(net "M_F_CPU1_SB_DQS_DP<5>")
		)
		(pad "DY32" smd circle
			(at -12.19454 19.445732 270)
			(size 0.4318 0.4318)
			(layers "F.Cu" "F.Mask" "F.Paste")
			(net "M_F_CPU1_SB_DQ<2>")
		)
		(pad "DY34" smd circle
			(at -10.566654 19.445732 270)
			(size 0.4318 0.4318)
			(layers "F.Cu" "F.Mask" "F.Paste")
			(net "M_G_CPU1_SB_CB<3>")
		)
		(pad "DY36" smd circle
			(at -8.939022 19.445732 270)
			(size 0.4318 0.4318)
			(layers "F.Cu" "F.Mask" "F.Paste")
			(net "M_G_CPU1_SB_DQS_DP<4>")
		)
		(pad "DY38" smd circle
			(at -7.311136 19.445732 270)
			(size 0.4318 0.4318)
			(layers "F.Cu" "F.Mask" "F.Paste")
			(net "M_G_CPU1_SB_CB<6>")
		)
		(pad "DY40" smd circle
			(at -5.68325 19.445732 270)
			(size 0.4318 0.4318)
			(layers "F.Cu" "F.Mask" "F.Paste")
			(net "M_G_CPU1_SB_CS_N<1>")
		)
		(pad "DY42" smd circle
			(at -4.055618 19.445732 270)
			(size 0.4318 0.4318)
			(layers "F.Cu" "F.Mask" "F.Paste")
			(net "GND")
		)
		(pad "DY44" smd circle
			(at -2.427732 19.445732 270)
			(size 0.4318 0.4318)
			(layers "F.Cu" "F.Mask" "F.Paste")
			(net "M_G_CPU1_SB_CA<3>")
		)
		(pad "DY47" smd circle
			(at 1.613916 19.555714 270)
			(size 0.4318 0.4318)
			(layers "F.Cu" "F.Mask" "F.Paste")
			(net "M_G_CPU1_SA_RSP<1>")
		)
		(pad "DY49" smd circle
			(at 3.241802 19.555714 270)
			(size 0.4318 0.4318)
			(layers "F.Cu" "F.Mask" "F.Paste")
			(net "M_F_CPU1_CLK_DN<0>")
		)
		(pad "DY51" smd circle
			(at 4.869434 19.555714 270)
			(size 0.4318 0.4318)
			(layers "F.Cu" "F.Mask" "F.Paste")
			(net "M_F_CPU1_SA_CA<6>")
		)
		(pad "DY53" smd circle
			(at 6.49732 19.555714 270)
			(size 0.4318 0.4318)
			(layers "F.Cu" "F.Mask" "F.Paste")
			(net "M_F_CPU1_SA_DQ<31>")
		)
		(pad "DY55" smd circle
			(at 8.124952 19.555714 270)
			(size 0.4318 0.4318)
			(layers "F.Cu" "F.Mask" "F.Paste")
			(net "M_F_CPU1_SA_DQS_DP<8>")
		)
		(pad "DY57" smd circle
			(at 9.752838 19.555714 270)
			(size 0.4318 0.4318)
			(layers "F.Cu" "F.Mask" "F.Paste")
			(net "M_F_CPU1_SA_DQ<26>")
		)
		(pad "DY59" smd circle
			(at 11.380724 19.555714 270)
			(size 0.4318 0.4318)
			(layers "F.Cu" "F.Mask" "F.Paste")
			(net "M_G_CPU1_SA_DQ<23>")
		)
		(pad "DY61" smd circle
			(at 13.008356 19.555714 270)
			(size 0.4318 0.4318)
			(layers "F.Cu" "F.Mask" "F.Paste")
			(net "M_G_CPU1_SA_DQS_DP<7>")
		)
		(pad "DY63" smd circle
			(at 14.635988 19.555714 270)
			(size 0.4318 0.4318)
			(layers "F.Cu" "F.Mask" "F.Paste")
			(net "M_G_CPU1_SA_DQ<18>")
		)
		(pad "DY65" smd circle
			(at 16.263874 19.555714 270)
			(size 0.4318 0.4318)
			(layers "F.Cu" "F.Mask" "F.Paste")
			(net "M_F_CPU1_SA_DQ<15>")
		)
		(pad "DY67" smd circle
			(at 17.89176 19.555714 270)
			(size 0.4318 0.4318)
			(layers "F.Cu" "F.Mask" "F.Paste")
			(net "M_F_CPU1_SA_DQS_DP<6>")
		)
		(pad "DY69" smd circle
			(at 19.519392 19.555714 270)
			(size 0.4318 0.4318)
			(layers "F.Cu" "F.Mask" "F.Paste")
			(net "M_F_CPU1_SA_DQ<10>")
		)
		(pad "DY71" smd circle
			(at 21.147278 19.555714 270)
			(size 0.4318 0.4318)
			(layers "F.Cu" "F.Mask" "F.Paste")
			(net "M_G_CPU1_SA_DQ<7>")
		)
		(pad "DY73" smd circle
			(at 22.77491 19.555714 270)
			(size 0.4318 0.4318)
			(layers "F.Cu" "F.Mask" "F.Paste")
			(net "M_G_CPU1_SA_DQS_DP<5>")
		)
		(pad "DY75" smd circle
			(at 24.402796 19.555714 270)
			(size 0.4318 0.4318)
			(layers "F.Cu" "F.Mask" "F.Paste")
			(net "M_G_CPU1_SA_DQ<2>")
		)
		(pad "DY77" smd circle
			(at 26.030682 19.555714 270)
			(size 0.4318 0.4318)
			(layers "F.Cu" "F.Mask" "F.Paste")
			(net "GND")
		)
		(pad "DY79" smd circle
			(at 27.658314 19.555714 270)
			(size 0.4318 0.4318)
			(layers "F.Cu" "F.Mask" "F.Paste")
			(net "M_H_CPU1_SA_DQ<0>")
		)
		(pad "DY81" smd circle
			(at 29.2862 19.555714 270)
			(size 0.4318 0.4318)
			(layers "F.Cu" "F.Mask" "F.Paste")
			(net "GND")
		)
		(pad "DY83" smd circle
			(at 30.914086 19.555714 270)
			(size 0.4318 0.4318)
			(layers "F.Cu" "F.Mask" "F.Paste")
			(net "GND")
		)
		(pad "DY85" smd circle
			(at 32.541718 19.555714 270)
			(size 0.4318 0.4318)
			(layers "F.Cu" "F.Mask" "F.Paste")
			(net "PVCCFA_EHV_FIVRA_CPU1")
		)
		(pad "DY87" smd circle
			(at 34.169604 19.555714 270)
			(size 0.4318 0.4318)
			(layers "F.Cu" "F.Mask" "F.Paste")
			(net "P5E_CPU1_PE3_TX_DN<2>")
		)
		(pad "DY89" smd circle
			(at 35.797236 19.555714 270)
			(size 0.4318 0.4318)
			(layers "F.Cu" "F.Mask" "F.Paste")
			(net "PVCCFA_EHV_FIVRA_CPU1")
		)
		(pad "DY91" smd oval
			(at 37.425122 19.555714)
			(size 0.381 0.4826)
			(drill
				(offset 0 -0.0508)
			)
			(layers "F.Cu" "F.Mask" "F.Paste")
			(net "P5E_CPU1_PE3_RX_DN<3>")
		)
		(pad "E5" smd oval
			(at -34.169604 -25.194514 135)
			(size 0.381 0.4826)
			(drill
				(offset 0 -0.0508)
			)
			(layers "F.Cu" "F.Mask" "F.Paste")
			(net "GND")
		)
		(pad "E7" smd oval
			(at -32.541718 -25.194514 135)
			(size 0.381 0.4826)
			(drill
				(offset 0 -0.0508)
			)
			(layers "F.Cu" "F.Mask" "F.Paste")
			(net "M_A_CPU1_SB_DQ<31>")
		)
		(pad "E9" smd circle
			(at -30.914086 -25.194514 270)
			(size 0.4318 0.4318)
			(layers "F.Cu" "F.Mask" "F.Paste")
			(net "M_A_CPU1_SB_DQS_DP<8>")
		)
		(pad "E11" smd circle
			(at -29.2862 -25.194514 270)
			(size 0.4318 0.4318)
			(layers "F.Cu" "F.Mask" "F.Paste")
			(net "M_A_CPU1_SB_DQ<26>")
		)
		(pad "E13" smd circle
			(at -27.658314 -25.194514 270)
			(size 0.4318 0.4318)
			(layers "F.Cu" "F.Mask" "F.Paste")
			(net "M_B_CPU1_SB_DQ<29>")
		)
		(pad "E15" smd circle
			(at -26.030682 -25.194514 270)
			(size 0.4318 0.4318)
			(layers "F.Cu" "F.Mask" "F.Paste")
			(net "M_B_CPU1_SB_DQS_DN<8>")
		)
		(pad "E17" smd circle
			(at -24.402796 -25.194514 270)
			(size 0.4318 0.4318)
			(layers "F.Cu" "F.Mask" "F.Paste")
			(net "M_B_CPU1_SB_DQ<26>")
		)
		(pad "E19" smd circle
			(at -22.77491 -25.194514 270)
			(size 0.4318 0.4318)
			(layers "F.Cu" "F.Mask" "F.Paste")
			(net "M_A_CPU1_SB_DQ<23>")
		)
		(pad "E21" smd circle
			(at -21.147278 -25.194514 270)
			(size 0.4318 0.4318)
			(layers "F.Cu" "F.Mask" "F.Paste")
			(net "M_A_CPU1_SB_DQS_DP<7>")
		)
		(pad "E23" smd circle
			(at -19.519392 -25.194514 270)
			(size 0.4318 0.4318)
			(layers "F.Cu" "F.Mask" "F.Paste")
			(net "M_A_CPU1_SB_DQ<18>")
		)
		(pad "E25" smd circle
			(at -17.89176 -25.194514 270)
			(size 0.4318 0.4318)
			(layers "F.Cu" "F.Mask" "F.Paste")
			(net "M_A_CPU1_SB_DQ<15>")
		)
		(pad "E27" smd circle
			(at -16.263874 -25.194514 270)
			(size 0.4318 0.4318)
			(layers "F.Cu" "F.Mask" "F.Paste")
			(net "M_A_CPU1_SB_DQS_DP<6>")
		)
		(pad "E29" smd circle
			(at -14.635988 -25.194514 270)
			(size 0.4318 0.4318)
			(layers "F.Cu" "F.Mask" "F.Paste")
			(net "M_A_CPU1_SB_DQ<10>")
		)
		(pad "E31" smd circle
			(at -13.008356 -25.194514 270)
			(size 0.4318 0.4318)
			(layers "F.Cu" "F.Mask" "F.Paste")
			(net "M_A_CPU1_SB_CB<3>")
		)
		(pad "E33" smd circle
			(at -11.380724 -25.194514 270)
			(size 0.4318 0.4318)
			(layers "F.Cu" "F.Mask" "F.Paste")
			(net "M_A_CPU1_SB_DQS_DP<4>")
		)
		(pad "E35" smd circle
			(at -9.752838 -25.194514 270)
			(size 0.4318 0.4318)
			(layers "F.Cu" "F.Mask" "F.Paste")
			(net "M_A_CPU1_SB_CB<6>")
		)
		(pad "E37" smd circle
			(at -8.124952 -25.194514 270)
			(size 0.4318 0.4318)
			(layers "F.Cu" "F.Mask" "F.Paste")
			(net "M_A_CPU1_SB_CS_N<3>")
		)
		(pad "E39" smd circle
			(at -6.49732 -25.194514 270)
			(size 0.4318 0.4318)
			(layers "F.Cu" "F.Mask" "F.Paste")
			(net "GND")
		)
		(pad "E41" smd circle
			(at -4.869434 -25.194514 270)
			(size 0.4318 0.4318)
			(layers "F.Cu" "F.Mask" "F.Paste")
			(net "M_A_CPU1_SB_CA<3>")
		)
		(pad "E43" smd circle
			(at -3.241802 -25.194514 270)
			(size 0.4318 0.4318)
			(layers "F.Cu" "F.Mask" "F.Paste")
			(net "M_A_CPU1_SB_CA<0>")
		)
		(pad "E45" smd circle
			(at -1.613916 -25.194514 270)
			(size 0.4318 0.4318)
			(layers "F.Cu" "F.Mask" "F.Paste")
			(net "M_A_CPU1_CLK_DP<1>")
		)
		(pad "E48" smd circle
			(at 2.427732 -25.084532 270)
			(size 0.4318 0.4318)
			(layers "F.Cu" "F.Mask" "F.Paste")
			(net "M_A_CPU1_SA_PAR")
		)
		(pad "E50" smd circle
			(at 4.055618 -25.084532 270)
			(size 0.4318 0.4318)
			(layers "F.Cu" "F.Mask" "F.Paste")
			(net "M_A_CPU1_SA_CA<5>")
		)
		(pad "E52" smd circle
			(at 5.68325 -25.084532 270)
			(size 0.4318 0.4318)
			(layers "F.Cu" "F.Mask" "F.Paste")
			(net "GND")
		)
		(pad "E54" smd circle
			(at 7.311136 -25.084532 270)
			(size 0.4318 0.4318)
			(layers "F.Cu" "F.Mask" "F.Paste")
			(net "M_A_CPU1_SA_CS_N<2>")
		)
		(pad "E56" smd circle
			(at 8.939022 -25.084532 270)
			(size 0.4318 0.4318)
			(layers "F.Cu" "F.Mask" "F.Paste")
			(net "M_A_CPU1_SA_CB<7>")
		)
		(pad "E58" smd circle
			(at 10.566654 -25.084532 270)
			(size 0.4318 0.4318)
			(layers "F.Cu" "F.Mask" "F.Paste")
			(net "M_A_CPU1_SA_DQS_DP<9>")
		)
		(pad "E60" smd circle
			(at 12.19454 -25.084532 270)
			(size 0.4318 0.4318)
			(layers "F.Cu" "F.Mask" "F.Paste")
			(net "M_A_CPU1_SA_CB<2>")
		)
		(pad "E62" smd circle
			(at 13.822426 -25.084532 270)
			(size 0.4318 0.4318)
			(layers "F.Cu" "F.Mask" "F.Paste")
			(net "M_A_CPU1_SA_DQ<31>")
		)
		(pad "E64" smd circle
			(at 15.450058 -25.084532 270)
			(size 0.4318 0.4318)
			(layers "F.Cu" "F.Mask" "F.Paste")
			(net "M_A_CPU1_SA_DQS_DP<8>")
		)
		(pad "E66" smd circle
			(at 17.07769 -25.084532 270)
			(size 0.4318 0.4318)
			(layers "F.Cu" "F.Mask" "F.Paste")
			(net "M_A_CPU1_SA_DQ<26>")
		)
		(pad "E68" smd circle
			(at 18.705576 -25.084532 270)
			(size 0.4318 0.4318)
			(layers "F.Cu" "F.Mask" "F.Paste")
			(net "M_A_CPU1_SA_DQ<23>")
		)
		(pad "E70" smd circle
			(at 20.333462 -25.084532 270)
			(size 0.4318 0.4318)
			(layers "F.Cu" "F.Mask" "F.Paste")
			(net "M_A_CPU1_SA_DQS_DP<7>")
		)
		(pad "E72" smd circle
			(at 21.961094 -25.084532 270)
			(size 0.4318 0.4318)
			(layers "F.Cu" "F.Mask" "F.Paste")
			(net "M_A_CPU1_SA_DQ<17>")
		)
		(pad "E74" smd circle
			(at 23.58898 -25.084532 270)
			(size 0.4318 0.4318)
			(layers "F.Cu" "F.Mask" "F.Paste")
			(net "GND")
		)
		(pad "E76" smd circle
			(at 25.216612 -25.084532 270)
			(size 0.4318 0.4318)
			(layers "F.Cu" "F.Mask" "F.Paste")
			(net "GND")
		)
		(pad "E78" smd circle
			(at 26.844498 -25.084532 270)
			(size 0.4318 0.4318)
			(layers "F.Cu" "F.Mask" "F.Paste")
			(net "GND")
		)
		(pad "E80" smd circle
			(at 28.472384 -25.084532 270)
			(size 0.4318 0.4318)
			(layers "F.Cu" "F.Mask" "F.Paste")
			(net "UPI_CPU0_CPU1_P2P2_DN<0>")
		)
		(pad "E82" smd circle
			(at 30.100016 -25.084532 270)
			(size 0.4318 0.4318)
			(layers "F.Cu" "F.Mask" "F.Paste")
			(net "UPI_CPU0_CPU1_P2P2_DP<1>")
		)
		(pad "E84" smd circle
			(at 31.727902 -25.084532 270)
			(size 0.4318 0.4318)
			(layers "F.Cu" "F.Mask" "F.Paste")
			(net "UPI_CPU1_CPU0_P2P2_DN<1>")
		)
		(pad "E86" smd oval
			(at 33.355534 -25.084532 45)
			(size 0.381 0.4826)
			(drill
				(offset 0 -0.0508)
			)
			(layers "F.Cu" "F.Mask" "F.Paste")
			(net "GND")
		)
		(pad "E88" smd oval
			(at 34.98342 -25.084532 45)
			(size 0.381 0.4826)
			(drill
				(offset 0 -0.0508)
			)
			(layers "F.Cu" "F.Mask" "F.Paste")
			(net "UPI_CPU1_CPU0_P2P2_DP<2>")
		)
		(pad "EA1" smd oval
			(at -37.425122 19.915886 180)
			(size 0.381 0.4826)
			(drill
				(offset 0 -0.0508)
			)
			(layers "F.Cu" "F.Mask" "F.Paste")
			(net "UPI_CPU0_CPU1_P0P1_DN<3>")
		)
		(pad "EA3" smd circle
			(at -35.797236 19.915886 270)
			(size 0.4318 0.4318)
			(layers "F.Cu" "F.Mask" "F.Paste")
			(net "PVCCFA_EHV_FIVRA_CPU1")
		)
		(pad "EA5" smd circle
			(at -34.169604 19.915886 270)
			(size 0.4318 0.4318)
			(layers "F.Cu" "F.Mask" "F.Paste")
			(net "UPI_CPU1_CPU0_P1P0_DP<2>")
		)
		(pad "EA7" smd circle
			(at -32.541718 19.915886 270)
			(size 0.4318 0.4318)
			(layers "F.Cu" "F.Mask" "F.Paste")
			(net "PVCCFA_EHV_FIVRA_CPU1")
		)
		(pad "EA9" smd circle
			(at -30.914086 19.915886 270)
			(size 0.4318 0.4318)
			(layers "F.Cu" "F.Mask" "F.Paste")
			(net "P5E_CPU1_PE2_RX_DN<12>")
		)
		(pad "EA11" smd circle
			(at -29.2862 19.915886 270)
			(size 0.4318 0.4318)
			(layers "F.Cu" "F.Mask" "F.Paste")
			(net "PVCCFA_EHV_FIVRA_CPU1")
		)
		(pad "EA13" smd circle
			(at -27.658314 19.915886 270)
			(size 0.4318 0.4318)
			(layers "F.Cu" "F.Mask" "F.Paste")
			(net "P5E_CPU1_PE2_TX_DN<12>")
		)
		(pad "EA15" smd circle
			(at -26.030682 19.915886 270)
			(size 0.4318 0.4318)
			(layers "F.Cu" "F.Mask" "F.Paste")
			(net "PVCCFA_EHV_FIVRA_CPU1")
		)
		(pad "EA17" smd circle
			(at -24.402796 19.915886 270)
			(size 0.4318 0.4318)
			(layers "F.Cu" "F.Mask" "F.Paste")
			(net "M_F_CPU1_SB_DQ<28>")
		)
		(pad "EA19" smd circle
			(at -22.77491 19.915886 270)
			(size 0.4318 0.4318)
			(layers "F.Cu" "F.Mask" "F.Paste")
			(net "M_F_CPU1_SB_DQ<27>")
		)
		(pad "EA21" smd circle
			(at -21.147278 19.915886 270)
			(size 0.4318 0.4318)
			(layers "F.Cu" "F.Mask" "F.Paste")
			(net "GND")
		)
		(pad "EA23" smd circle
			(at -19.519392 19.915886 270)
			(size 0.4318 0.4318)
			(layers "F.Cu" "F.Mask" "F.Paste")
			(net "M_G_CPU1_SB_DQ<22>")
		)
		(pad "EA25" smd circle
			(at -17.89176 19.915886 270)
			(size 0.4318 0.4318)
			(layers "F.Cu" "F.Mask" "F.Paste")
			(net "M_G_CPU1_SB_DQ<19>")
		)
		(pad "EA27" smd circle
			(at -16.263874 19.915886 270)
			(size 0.4318 0.4318)
			(layers "F.Cu" "F.Mask" "F.Paste")
			(net "GND")
		)
		(pad "EA29" smd circle
			(at -14.635988 19.915886 270)
			(size 0.4318 0.4318)
			(layers "F.Cu" "F.Mask" "F.Paste")
			(net "M_F_CPU1_SB_DQ<6>")
		)
		(pad "EA31" smd circle
			(at -13.008356 19.915886 270)
			(size 0.4318 0.4318)
			(layers "F.Cu" "F.Mask" "F.Paste")
			(net "M_F_CPU1_SB_DQ<3>")
		)
	)
)
